# S9S_MB_2U (Grand Teton) — schematic netlist excerpt (pin names and nets, part order shuffled) for the footprints in the layout excerpt that follows; sources: Cadence DE-HDL packaged netlist, KiCad conversion of 03242023_DA0F0TMBIJ0_F0T_Motherboard_J_brd_V01_OCP.brd

PU10_P0_4  ISL99390FRZTR5935  ISL99390FRZ-TR5935 IC  pkg QFN21_6X5XB  page 268
  VOS  = PVCCIN_CPU0_VOS4
  AGND  = GND
  VCC  = PVCCIN_CPU0_VDD4
  PVCC  = PVCCIN_CPU0_PVCC
  PGND1  = GND
  GL1  = NC
  PGND2  = GND
  SW  = SW_PVCCIN_CPU0_SW4
  VIN1  = SW_P12V_PVCCIN_CPU0_FLT
  VIN2  = SW_P12V_PVCCIN_CPU0_FLT
  DNC  = NC
  PHASE  = SW_PVCCIN_CPU0_BOOTR4
  BOOT  = SW_PVCCIN_CPU0_BOOT4
  PWM  = PVCCIN_CPU0_PWM4
  EN  = PVCCIN_CPU0_VDD4
  TOUT_FLT  = PVCCIN_CPU0_ATSEN
  LSET  = PVCCIN_CPU0_LSET4
  IOUT  = PVCCIN_CPU0_IMON4
  REFIN  = PVCCIN_CPU0_VREF
  PGND3  = GND
  GL2  = NC

(kicad_pcb
	(version 20260206)
	(generator "pcbnew")
	(generator_version "10.0")
	(general
		(thickness 1.6)
		(legacy_teardrops no)
	)
	(paper "A4")
	(title_block
		(title "03242023_DA0F0TMBIJ0_F0T_Motherboard_J_brd_V01_OCP.brd")
		(comment 1 "Grand Teton / footprints 911-911 of 6105")
	)
	(layers
		(0 "F.Cu" signal "TOP")
		(4 "In1.Cu" signal "GND")
		(6 "In2.Cu" signal "IN1")
		(8 "In3.Cu" signal "GND1")
		(10 "In4.Cu" signal "IN2")
		(12 "In5.Cu" signal "GND2")
		(14 "In6.Cu" signal "IN3")
		(16 "In7.Cu" signal "GND3")
		(18 "In8.Cu" signal "VCC")
		(20 "In9.Cu" signal "VCC1")
		(22 "In10.Cu" signal "GND4")
		(24 "In11.Cu" signal "IN4")
		(26 "In12.Cu" signal "GND5")
		(28 "In13.Cu" signal "IN5")
		(30 "In14.Cu" signal "GND6")
		(32 "In15.Cu" signal "IN6")
		(34 "In16.Cu" signal "GND7")
		(2 "B.Cu" signal "BOTTOM")
		(9 "F.Adhes" user "F.Adhesive")
		(11 "B.Adhes" user "B.Adhesive")
		(13 "F.Paste" user "Package Geometry/Pastemask Top")
		(15 "B.Paste" user "Package Geometry/Pastemask Bottom")
		(5 "F.SilkS" user "Ref Des/Silkscreen Top")
		(7 "B.SilkS" user "Ref Des/Silkscreen Bottom")
		(1 "F.Mask" user "Board Geometry/Soldermask Top")
		(3 "B.Mask" user "Board Geometry/Soldermask Bottom")
		(17 "Dwgs.User" user "User.Drawings")
		(19 "Cmts.User" user "User.Comments")
		(21 "Eco1.User" user "User.Eco1")
		(23 "Eco2.User" user "User.Eco2")
		(25 "Edge.Cuts" user "Board Geometry/Outline")
		(27 "Margin" user)
		(31 "F.CrtYd" user "Package Geometry/Place Bound Top")
		(29 "B.CrtYd" user "Package Geometry/Place Bound Bottom")
		(35 "F.Fab" user "Ref Des/Assembly Top")
		(33 "B.Fab" user "Ref Des/Assembly Bottom")
	)
	(footprint ""
		(layer "F.Cu")
		(at 369.419124 -333.716122)
		(property "Reference" "PU10_P0_4"
			(at 3.442716 -12.403836 0)
			(unlocked yes)
			(layer "F.SilkS")
			(effects
				(font
					(size 0.7874 0.5842)
					(thickness 0.1524)
				)
				(justify left)
			)
		)
		(property "Value" ""
			(at 0 0 0)
			(layer "F.Fab")
			(effects
				(font
					(size 1.27 1.27)
				)
			)
		)
		(duplicate_pad_numbers_are_jumpers no)
		(fp_line
			(start -2.500122 -2.999994)
			(end -2.24409 -2.999994)
			(stroke
				(width 0.1524)
				(type default)
			)
			(layer "F.SilkS")
		)
		(fp_line
			(start -2.500122 -2.529078)
			(end -2.500122 -2.999994)
			(stroke
				(width 0.1524)
				(type default)
			)
			(layer "F.SilkS")
		)
		(fp_line
			(start -2.500122 0.6604)
			(end -2.500122 0.229108)
			(stroke
				(width 0.1524)
				(type default)
			)
			(layer "F.SilkS")
		)
		(fp_line
			(start -2.500122 2.999994)
			(end -2.500122 2.339594)
			(stroke
				(width 0.1524)
				(type default)
			)
			(layer "F.SilkS")
		)
		(fp_line
			(start -2.2987 2.999994)
			(end -2.500122 2.999994)
			(stroke
				(width 0.1524)
				(type default)
			)
			(layer "F.SilkS")
		)
		(fp_line
			(start 2.31394 -2.999994)
			(end 2.500122 -2.999994)
			(stroke
				(width 0.1524)
				(type default)
			)
			(layer "F.SilkS")
		)
		(fp_line
			(start 2.500122 -2.999994)
			(end 2.500122 -2.44348)
			(stroke
				(width 0.1524)
				(type default)
			)
			(layer "F.SilkS")
		)
		(fp_line
			(start 2.500122 2.339594)
			(end 2.500122 2.999994)
			(stroke
				(width 0.1524)
				(type default)
			)
			(layer "F.SilkS")
		)
		(fp_line
			(start 2.500122 2.999994)
			(end 2.2987 2.999994)
			(stroke
				(width 0.1524)
				(type default)
			)
			(layer "F.SilkS")
		)
		(fp_poly
			(pts
				(xy -2.168652 -3.624834) (xy -2.676652 -2.608834) (xy -3.184652 -3.624834)
			)
			(stroke
				(width 0)
				(type default)
			)
			(fill yes)
			(layer "F.SilkS")
		)
		(fp_line
			(start -2.500122 -2.999994)
			(end 2.500122 -2.999994)
			(stroke
				(width 0.1)
				(type default)
			)
			(layer "F.Fab")
		)
		(fp_line
			(start -2.500122 2.999994)
			(end -2.500122 -2.999994)
			(stroke
				(width 0.1)
				(type default)
			)
			(layer "F.Fab")
		)
		(fp_line
			(start 2.500122 -2.999994)
			(end 2.500122 2.999994)
			(stroke
				(width 0.1)
				(type default)
			)
			(layer "F.Fab")
		)
		(fp_line
			(start 2.500122 2.999994)
			(end -2.500122 2.999994)
			(stroke
				(width 0.1)
				(type default)
			)
			(layer "F.Fab")
		)
		(fp_poly
			(pts
				(xy -4.218432 -2.783078) (xy -4.218432 -1.767078) (xy -3.202432 -2.275078)
			)
			(stroke
				(width 0)
				(type default)
			)
			(fill yes)
			(layer "F.Fab")
		)
		(pad "1" smd rect
			(at -2.400046 -2.275078 90)
			(size 0.2286 0.6096)
			(layers "F.Cu" "F.Mask" "F.Paste")
			(net "PVCCIN_CPU0_VOS4")
		)
		(pad "2" smd rect
			(at -2.400046 -1.82499 90)
			(size 0.2286 0.6096)
			(layers "F.Cu" "F.Mask" "F.Paste")
			(net "GND")
		)
		(pad "3" smd rect
			(at -2.400046 -1.374902 90)
			(size 0.2286 0.6096)
			(layers "F.Cu" "F.Mask" "F.Paste")
			(net "PVCCIN_CPU0_VDD4")
		)
		(pad "4" smd rect
			(at -2.400046 -0.925068 90)
			(size 0.2286 0.6096)
			(layers "F.Cu" "F.Mask" "F.Paste")
			(net "PVCCIN_CPU0_PVCC")
		)
		(pad "5" smd rect
			(at -2.400046 -0.47498 90)
			(size 0.2286 0.6096)
			(layers "F.Cu" "F.Mask" "F.Paste")
			(net "GND")
		)
		(pad "6" smd rect
			(at -2.400046 -0.024892 90)
			(size 0.2286 0.6096)
			(layers "F.Cu" "F.Mask" "F.Paste")
			(net "Net_8553")
		)
		(pad "7_9-20_24" smd circle
			(at 0 1.150112 90)
			(size 0 0)
			(layers "F.Cu" "F.Mask" "F.Paste")
			(net "GND")
		)
		(pad "10_19" smd rect
			(at 0 2.899918 90)
			(size 0.6096 4.318)
			(layers "F.Cu" "F.Mask" "F.Paste")
			(net "SW_PVCCIN_CPU0_SW4")
		)
		(pad "25_29" smd rect
			(at 1.549908 -1.279906 270)
			(size 2.0574 2.3114)
			(layers "F.Cu" "F.Mask" "F.Paste")
			(net "SW_P12V_PVCCIN_CPU0_FLT")
		)
		(pad "30" smd rect
			(at 2.05994 -2.899918)
			(size 0.2286 0.6096)
			(layers "F.Cu" "F.Mask" "F.Paste")
			(net "SW_P12V_PVCCIN_CPU0_FLT")
		)
		(pad "31" smd rect
			(at 1.610106 -2.899918)
			(size 0.2286 0.6096)
			(layers "F.Cu" "F.Mask" "F.Paste")
			(net "Net_8554")
		)
		(pad "32" smd rect
			(at 1.160018 -2.899918)
			(size 0.2286 0.6096)
			(layers "F.Cu" "F.Mask" "F.Paste")
			(net "SW_PVCCIN_CPU0_BOOTR4")
		)
		(pad "33" smd rect
			(at 0.70993 -2.899918)
			(size 0.2286 0.6096)
			(layers "F.Cu" "F.Mask" "F.Paste")
			(net "SW_PVCCIN_CPU0_BOOT4")
		)
		(pad "34" smd rect
			(at 0.260096 -2.899918)
			(size 0.2286 0.6096)
			(layers "F.Cu" "F.Mask" "F.Paste")
			(net "PVCCIN_CPU0_PWM4")
		)
		(pad "35" smd rect
			(at -0.189992 -2.899918)
			(size 0.2286 0.6096)
			(layers "F.Cu" "F.Mask" "F.Paste")
			(net "PVCCIN_CPU0_VDD4")
		)
		(pad "36" smd rect
			(at -0.64008 -2.899918)
			(size 0.2286 0.6096)
			(layers "F.Cu" "F.Mask" "F.Paste")
			(net "PVCCIN_CPU0_ATSEN")
		)
		(pad "37" smd rect
			(at -1.089914 -2.899918)
			(size 0.2286 0.6096)
			(layers "F.Cu" "F.Mask" "F.Paste")
			(net "PVCCIN_CPU0_LSET4")
		)
		(pad "38" smd rect
			(at -1.540002 -2.899918)
			(size 0.2286 0.6096)
			(layers "F.Cu" "F.Mask" "F.Paste")
			(net "PVCCIN_CPU0_IMON4")
		)
		(pad "39" smd rect
			(at -1.99009 -2.899918)
			(size 0.2286 0.6096)
			(layers "F.Cu" "F.Mask" "F.Paste")
			(net "PVCCIN_CPU0_VREF")
		)
		(pad "40" smd rect
			(at -0.87503 -1.27508)
			(size 1.7526 1.9558)
			(layers "F.Cu" "F.Mask" "F.Paste")
			(net "GND")
		)
		(pad "41" smd rect
			(at -1.525016 0.249936 270)
			(size 0.3048 0.4572)
			(layers "F.Cu" "F.Mask" "F.Paste")
			(net "Net_8552")
		)
		(zone
			(layer "F.Cu")
			(hatch none 0.5)
			(connect_pads
				(clearance 0)
			)
			(min_thickness 0.25)
			(keepout
				(tracks not_allowed)
				(vias allowed)
				(pads allowed)
				(copperpour not_allowed)
				(footprints allowed)
			)
			(placement
				(enabled no)
				(sheetname "")
			)
			(fill
				(thermal_gap 0.5)
				(thermal_bridge_width 0.5)
				(island_removal_mode 0)
			)
			(polygon
				(pts
					(xy 368.173508 -333.652368) (xy 368.468402 -333.652368) (xy 368.468402 -332.966822) (xy 366.919002 -332.966822)
					(xy 366.919002 -333.423514) (xy 367.614708 -333.423514) (xy 367.614708 -333.262986) (xy 368.173508 -333.262986)
				)
			)
		)
		(zone
			(layer "F.Cu")
			(hatch none 0.5)
			(connect_pads
				(clearance 0)
			)
			(min_thickness 0.25)
			(keepout
				(tracks not_allowed)
				(vias allowed)
				(pads allowed)
				(copperpour not_allowed)
				(footprints allowed)
			)
			(placement
				(enabled no)
				(sheetname "")
			)
			(fill
				(thermal_gap 0.5)
				(thermal_bridge_width 0.5)
				(island_removal_mode 0)
			)
			(polygon
				(pts
					(xy 366.919002 -330.716128) (xy 366.919002 -331.465428) (xy 371.919246 -331.465428) (xy 371.919246 -330.716128)
					(xy 371.6909 -330.716128) (xy 371.6909 -331.109828) (xy 371.628924 -331.171804) (xy 367.209324 -331.171804)
					(xy 367.209324 -330.716128)
				)
			)
		)
	)
)
